# S9S_MB_2U (Grand Teton) — schematic netlist excerpt (pin names and nets, part order shuffled) for the footprints in the layout excerpt that follows; sources: Cadence DE-HDL packaged netlist, KiCad conversion of 03242023_DA0F0TMBIJ0_F0T_Motherboard_J_brd_V01_OCP.brd

PC307_P0_1  Q_CAP  22UF 16V 20% X6S  pkg C0805  page 267 : A = SW_P12V_PVCCIN_CPU0_FLT ; B = GND
R3940  Q_RES  0 5% EMPTY  pkg 0402LF  page 250 : A = P12V_E1S_0_ISENSE_MPS_MAM ; B = P12V_E1S_0_ISENSE_MAM
C63  Q_CAP  10UF 16V 10% X6S  pkg C0805  page 102 : A = P12V_S3_AUX_CPU1_NVDIMM ; B = GND

(kicad_pcb
	(version 20260206)
	(generator "pcbnew")
	(generator_version "10.0")
	(general
		(thickness 1.6)
		(legacy_teardrops no)
	)
	(paper "A4")
	(title_block
		(title "03242023_DA0F0TMBIJ0_F0T_Motherboard_J_brd_V01_OCP.brd")
		(comment 1 "Grand Teton / footprints 4943-4945 of 6105")
	)
	(layers
		(0 "F.Cu" signal "TOP")
		(4 "In1.Cu" signal "GND")
		(6 "In2.Cu" signal "IN1")
		(8 "In3.Cu" signal "GND1")
		(10 "In4.Cu" signal "IN2")
		(12 "In5.Cu" signal "GND2")
		(14 "In6.Cu" signal "IN3")
		(16 "In7.Cu" signal "GND3")
		(18 "In8.Cu" signal "VCC")
		(20 "In9.Cu" signal "VCC1")
		(22 "In10.Cu" signal "GND4")
		(24 "In11.Cu" signal "IN4")
		(26 "In12.Cu" signal "GND5")
		(28 "In13.Cu" signal "IN5")
		(30 "In14.Cu" signal "GND6")
		(32 "In15.Cu" signal "IN6")
		(34 "In16.Cu" signal "GND7")
		(2 "B.Cu" signal "BOTTOM")
		(9 "F.Adhes" user "F.Adhesive")
		(11 "B.Adhes" user "B.Adhesive")
		(13 "F.Paste" user "Package Geometry/Pastemask Top")
		(15 "B.Paste" user "Package Geometry/Pastemask Bottom")
		(5 "F.SilkS" user "Ref Des/Silkscreen Top")
		(7 "B.SilkS" user "Ref Des/Silkscreen Bottom")
		(1 "F.Mask" user "Board Geometry/Soldermask Top")
		(3 "B.Mask" user "Board Geometry/Soldermask Bottom")
		(17 "Dwgs.User" user "User.Drawings")
		(19 "Cmts.User" user "User.Comments")
		(21 "Eco1.User" user "User.Eco1")
		(23 "Eco2.User" user "User.Eco2")
		(25 "Edge.Cuts" user "Board Geometry/Outline")
		(27 "Margin" user)
		(31 "F.CrtYd" user "Package Geometry/Place Bound Top")
		(29 "B.CrtYd" user "Package Geometry/Place Bound Bottom")
		(35 "F.Fab" user "Ref Des/Assembly Top")
		(33 "B.Fab" user "Ref Des/Assembly Bottom")
	)
	(footprint ""
		(layer "B.Cu")
		(at 346.441014 -337.564984 -90)
		(property "Reference" "PC307_P0_1"
			(at 0 0 90)
			(layer "B.SilkS")
			(hide yes)
			(effects
				(font
					(size 1.27 1.27)
				)
				(justify mirror)
			)
		)
		(property "Value" ""
			(at 0 0 90)
			(layer "B.Fab")
			(effects
				(font
					(size 1.27 1.27)
				)
				(justify mirror)
			)
		)
		(duplicate_pad_numbers_are_jumpers no)
		(fp_line
			(start -1.524 0.762)
			(end 1.524 0.762)
			(stroke
				(width 0.1524)
				(type default)
			)
			(layer "B.SilkS")
		)
		(fp_line
			(start 1.524 0.762)
			(end 1.524 -0.762)
			(stroke
				(width 0.1524)
				(type default)
			)
			(layer "B.SilkS")
		)
		(fp_line
			(start -1.524 -0.762)
			(end -1.524 0.762)
			(stroke
				(width 0.1524)
				(type default)
			)
			(layer "B.SilkS")
		)
		(fp_line
			(start 1.524 -0.762)
			(end -1.524 -0.762)
			(stroke
				(width 0.1524)
				(type default)
			)
			(layer "B.SilkS")
		)
		(fp_line
			(start -1.1049 0.724916)
			(end -1.1049 -0.724916)
			(stroke
				(width 0.1)
				(type default)
			)
			(layer "B.Fab")
		)
		(fp_line
			(start 1.1049 0.724916)
			(end -1.1049 0.724916)
			(stroke
				(width 0.1)
				(type default)
			)
			(layer "B.Fab")
		)
		(fp_line
			(start -1.1049 -0.724916)
			(end 1.1049 -0.724916)
			(stroke
				(width 0.1)
				(type default)
			)
			(layer "B.Fab")
		)
		(fp_line
			(start 1.1049 -0.724916)
			(end 1.1049 0.724916)
			(stroke
				(width 0.1)
				(type default)
			)
			(layer "B.Fab")
		)
		(pad "1" smd rect
			(at 0.889 0 270)
			(size 1.016 1.27)
			(layers "B.Cu" "B.Mask" "B.Paste")
			(net "SW_P12V_PVCCIN_CPU0_FLT")
		)
		(pad "2" smd rect
			(at -0.889 0 270)
			(size 1.016 1.27)
			(layers "B.Cu" "B.Mask" "B.Paste")
			(net "GND")
		)
	)
	(footprint ""
		(layer "B.Cu")
		(at 27.304746 -321.554856 -90)
		(property "Reference" "C63"
			(at 0 0 90)
			(layer "B.SilkS")
			(hide yes)
			(effects
				(font
					(size 1.27 1.27)
				)
				(justify mirror)
			)
		)
		(property "Value" ""
			(at 0 0 90)
			(layer "B.Fab")
			(effects
				(font
					(size 1.27 1.27)
				)
				(justify mirror)
			)
		)
		(duplicate_pad_numbers_are_jumpers no)
		(fp_line
			(start -1.524 0.762)
			(end 1.524 0.762)
			(stroke
				(width 0.1524)
				(type default)
			)
			(layer "B.SilkS")
		)
		(fp_line
			(start 1.524 0.762)
			(end 1.524 -0.762)
			(stroke
				(width 0.1524)
				(type default)
			)
			(layer "B.SilkS")
		)
		(fp_line
			(start -1.524 -0.762)
			(end -1.524 0.762)
			(stroke
				(width 0.1524)
				(type default)
			)
			(layer "B.SilkS")
		)
		(fp_line
			(start 1.524 -0.762)
			(end -1.524 -0.762)
			(stroke
				(width 0.1524)
				(type default)
			)
			(layer "B.SilkS")
		)
		(fp_line
			(start -1.1049 0.724916)
			(end -1.1049 -0.724916)
			(stroke
				(width 0.1)
				(type default)
			)
			(layer "B.Fab")
		)
		(fp_line
			(start 1.1049 0.724916)
			(end -1.1049 0.724916)
			(stroke
				(width 0.1)
				(type default)
			)
			(layer "B.Fab")
		)
		(fp_line
			(start -1.1049 -0.724916)
			(end 1.1049 -0.724916)
			(stroke
				(width 0.1)
				(type default)
			)
			(layer "B.Fab")
		)
		(fp_line
			(start 1.1049 -0.724916)
			(end 1.1049 0.724916)
			(stroke
				(width 0.1)
				(type default)
			)
			(layer "B.Fab")
		)
		(pad "1" smd rect
			(at 0.889 0 270)
			(size 1.016 1.27)
			(layers "B.Cu" "B.Mask" "B.Paste")
			(net "P12V_S3_AUX_CPU1_NVDIMM")
		)
		(pad "2" smd rect
			(at -0.889 0 270)
			(size 1.016 1.27)
			(layers "B.Cu" "B.Mask" "B.Paste")
			(net "GND")
		)
	)
	(footprint ""
		(layer "B.Cu")
		(at 41.830244 -100.55733 90)
		(property "Reference" "R3940"
			(at 0 0 90)
			(layer "B.SilkS")
			(hide yes)
			(effects
				(font
					(size 1.27 1.27)
				)
				(justify mirror)
			)
		)
		(property "Value" ""
			(at 0 0 90)
			(layer "B.Fab")
			(effects
				(font
					(size 1.27 1.27)
				)
				(justify mirror)
			)
		)
		(duplicate_pad_numbers_are_jumpers no)
		(fp_line
			(start 0.7874 -0.4064)
			(end -0.7874 -0.4064)
			(stroke
				(width 0.1524)
				(type default)
			)
			(layer "B.SilkS")
		)
		(fp_line
			(start -0.7874 -0.4064)
			(end -0.7874 0.4064)
			(stroke
				(width 0.1524)
				(type default)
			)
			(layer "B.SilkS")
		)
		(fp_line
			(start 0.7874 0.4064)
			(end 0.7874 -0.4064)
			(stroke
				(width 0.1524)
				(type default)
			)
			(layer "B.SilkS")
		)
		(fp_line
			(start -0.7874 0.4064)
			(end 0.7874 0.4064)
			(stroke
				(width 0.1524)
				(type default)
			)
			(layer "B.SilkS")
		)
		(fp_line
			(start 0.67945 -0.305054)
			(end 0.12065 -0.305054)
			(stroke
				(width 0.1)
				(type default)
			)
			(layer "B.Fab")
		)
		(fp_line
			(start 0.12065 -0.305054)
			(end 0.12065 -0.2794)
			(stroke
				(width 0.1)
				(type default)
			)
			(layer "B.Fab")
		)
		(fp_line
			(start -0.12065 -0.3048)
			(end -0.67945 -0.3048)
			(stroke
				(width 0.1)
				(type default)
			)
			(layer "B.Fab")
		)
		(fp_line
			(start -0.67945 -0.3048)
			(end -0.67945 0.3048)
			(stroke
				(width 0.1)
				(type default)
			)
			(layer "B.Fab")
		)
		(fp_line
			(start 0.12065 -0.2794)
			(end -0.12065 -0.2794)
			(stroke
				(width 0.1)
				(type default)
			)
			(layer "B.Fab")
		)
		(fp_line
			(start -0.12065 -0.2794)
			(end -0.12065 -0.3048)
			(stroke
				(width 0.1)
				(type default)
			)
			(layer "B.Fab")
		)
		(fp_line
			(start 0.12065 0.2794)
			(end 0.12065 0.3048)
			(stroke
				(width 0.1)
				(type default)
			)
			(layer "B.Fab")
		)
		(fp_line
			(start -0.120396 0.2794)
			(end 0.12065 0.2794)
			(stroke
				(width 0.1)
				(type default)
			)
			(layer "B.Fab")
		)
		(fp_line
			(start 0.67945 0.3048)
			(end 0.67945 -0.305054)
			(stroke
				(width 0.1)
				(type default)
			)
			(layer "B.Fab")
		)
		(fp_line
			(start 0.12065 0.3048)
			(end 0.67945 0.3048)
			(stroke
				(width 0.1)
				(type default)
			)
			(layer "B.Fab")
		)
		(fp_line
			(start -0.120396 0.3048)
			(end -0.120396 0.2794)
			(stroke
				(width 0.1)
				(type default)
			)
			(layer "B.Fab")
		)
		(fp_line
			(start -0.67945 0.3048)
			(end -0.120396 0.3048)
			(stroke
				(width 0.1)
				(type default)
			)
			(layer "B.Fab")
		)
		(pad "1" smd rect
			(at 0.40005 0 90)
			(size 0.4572 0.508)
			(layers "B.Cu" "B.Mask" "B.Paste")
			(net "P12V_E1S_0_ISENSE_MPS_MAM")
		)
		(pad "2" smd rect
			(at -0.40005 0 90)
			(size 0.4572 0.508)
			(layers "B.Cu" "B.Mask" "B.Paste")
			(net "P12V_E1S_0_ISENSE_MAM")
		)
	)
)
